(kicad_pcb
	(version 20211014)
	(generator pcbnew)
	(general
    (thickness 1.6)
  )
	(paper "A4")
	(title_block
    (title "SA800U (Snapdragon 845) Baseboard")
    (date "2023-10-19")
    (rev "1.0.3")
    (company "Antmicro Ltd.")
    (comment 1 "www.antmicro.com")
		(comment 9 "footprints 81-89 of 589")
	)
	(layers
    (0 "F.Cu" signal)
    (1 "In1.Cu" power)
    (2 "In2.Cu" signal)
    (3 "In3.Cu" signal)
    (4 "In4.Cu" power)
    (31 "B.Cu" signal)
    (32 "B.Adhes" user "B.Adhesive")
    (33 "F.Adhes" user "F.Adhesive")
    (34 "B.Paste" user)
    (35 "F.Paste" user)
    (36 "B.SilkS" user "B.Silkscreen")
    (37 "F.SilkS" user "F.Silkscreen")
    (38 "B.Mask" user)
    (39 "F.Mask" user)
    (40 "Dwgs.User" user "User.Drawings")
    (41 "Cmts.User" user "User.Comments")
    (42 "Eco1.User" user "User.Eco1")
    (43 "Eco2.User" user "User.Eco2")
    (44 "Edge.Cuts" user)
    (45 "Margin" user)
    (46 "B.CrtYd" user "B.Courtyard")
    (47 "F.CrtYd" user "F.Courtyard")
    (48 "B.Fab" user)
    (49 "F.Fab" user)
  )
	(footprint "sa800u-baseboard-hw-footprints:C_0402_1005Metric" (layer "F.Cu")
    (tedit 616D63CF)
    (at 99 103.8 180)
    (descr "Capacitor SMD 0402")
    (tags "capacitor SMD 0402")
    (property "Author" "Antmicro")
    (property "Dielectric" "X5R")
    (property "License" "Apache-2.0")
    (property "MPN" "GRM155R61H104KE14D")
    (property "Manufacturer" "Murata")
    (property "Sheetfile" "ethernet-controller.kicad_sch")
    (property "Sheetname" "Ethernet Controller")
    (property "Val" "100n")
    (property "Voltage" "50V")
    (attr smd)
    (fp_text reference "C12" (at 1.12 -1.24 180) (layer "F.SilkS")
      (effects (font (size 0.7 0.7) (thickness 0.15)) (justify left bottom))
    )
    (fp_text value "C_100n_0402" (at 0 1.4 180) (layer "F.Fab")
      (effects (font (size 0.7 0.7) (thickness 0.15)) (justify left bottom))
    )
    (fp_text user "License: Apache-2.0" (at -0.932 5.17 180) (layer "F.Fab") hide
      (effects (font (size 0.7 0.7) (thickness 0.15)) (justify left bottom))
    )
    (fp_text user "Author: Antmicro" (at -0.932 4.17 180) (layer "F.Fab") hide
      (effects (font (size 0.7 0.7) (thickness 0.15)) (justify left bottom))
    )
    (fp_text user "${REFERENCE}" (at -0.932 3.168 180) (layer "F.Fab") hide
      (effects (font (size 0.7 0.7) (thickness 0.15)) (justify left bottom))
    )
    (fp_rect (start -0.94 -0.47) (end 0.94 0.47) (layer "F.CrtYd") (width 0.05) (fill none))
    (fp_rect (start -0.499 -0.249) (end 0.499 0.249) (layer "F.Fab") (width 0.15) (fill none))
    (pad "1" smd roundrect (at -0.484 0 180) (size 0.59 0.64) (layers "F.Cu" "F.Paste" "F.Mask") (roundrect_rratio 0.25)
      (net 181 "/Ethernet Controller/ETH_1V0") (pintype "passive"))
    (pad "2" smd roundrect (at 0.484 0 180) (size 0.59 0.64) (layers "F.Cu" "F.Paste" "F.Mask") (roundrect_rratio 0.25)
      (net 1 "GND") (pintype "passive"))
  )
	(footprint "sa800u-baseboard-hw-footprints:C_0402_1005Metric" (layer "F.Cu")
    (tedit 616D63CF)
    (at 95.519764 103.700522)
    (descr "Capacitor SMD 0402")
    (tags "capacitor SMD 0402")
    (property "Author" "Antmicro")
    (property "Dielectric" "X5R")
    (property "License" "Apache-2.0")
    (property "MPN" "GRM155R61H104KE14D")
    (property "Manufacturer" "Murata")
    (property "Sheetfile" "ethernet-controller.kicad_sch")
    (property "Sheetname" "Ethernet Controller")
    (property "Val" "100n")
    (property "Voltage" "50V")
    (attr smd)
    (fp_text reference "C15" (at -3.059764 0.339478) (layer "F.SilkS")
      (effects (font (size 0.7 0.7) (thickness 0.15)) (justify left bottom))
    )
    (fp_text value "C_100n_0402" (at 0 1.4) (layer "F.Fab")
      (effects (font (size 0.7 0.7) (thickness 0.15)) (justify left bottom))
    )
    (fp_text user "License: Apache-2.0" (at -0.932 5.17) (layer "F.Fab") hide
      (effects (font (size 0.7 0.7) (thickness 0.15)) (justify left bottom))
    )
    (fp_text user "${REFERENCE}" (at -0.932 3.168) (layer "F.Fab") hide
      (effects (font (size 0.7 0.7) (thickness 0.15)) (justify left bottom))
    )
    (fp_text user "Author: Antmicro" (at -0.932 4.17) (layer "F.Fab") hide
      (effects (font (size 0.7 0.7) (thickness 0.15)) (justify left bottom))
    )
    (fp_rect (start -0.94 -0.47) (end 0.94 0.47) (layer "F.CrtYd") (width 0.05) (fill none))
    (fp_rect (start -0.499 -0.249) (end 0.499 0.249) (layer "F.Fab") (width 0.15) (fill none))
    (pad "1" smd roundrect (at -0.484 0) (size 0.59 0.64) (layers "F.Cu" "F.Paste" "F.Mask") (roundrect_rratio 0.25)
      (net 181 "/Ethernet Controller/ETH_1V0") (pintype "passive"))
    (pad "2" smd roundrect (at 0.484 0) (size 0.59 0.64) (layers "F.Cu" "F.Paste" "F.Mask") (roundrect_rratio 0.25)
      (net 1 "GND") (pintype "passive"))
  )
	(footprint "sa800u-baseboard-hw-footprints:C_0402_1005Metric" (layer "F.Cu")
    (tedit 616D63CF)
    (at 93.928774 105.432933 180)
    (descr "Capacitor SMD 0402")
    (tags "capacitor SMD 0402")
    (property "Author" "Antmicro")
    (property "DNP" "DNP")
    (property "Dielectric" "")
    (property "License" "Apache-2.0")
    (property "MPN" "GRM155R61A475MEAAD")
    (property "Manufacturer" "Murata")
    (property "Sheetfile" "ethernet-controller.kicad_sch")
    (property "Sheetname" "Ethernet Controller")
    (property "Val" "4u7")
    (property "Voltage" "")
    (attr exclude_from_pos_files)
    (fp_text reference "C8" (at 2.438774 -0.347067 180) (layer "F.SilkS")
      (effects (font (size 0.7 0.7) (thickness 0.15)) (justify left bottom))
    )
    (fp_text value "C_4u7_0402" (at 0 1.4 180) (layer "F.Fab")
      (effects (font (size 0.7 0.7) (thickness 0.15)) (justify left bottom))
    )
    (fp_text user "License: Apache-2.0" (at -0.932 5.17 180) (layer "F.Fab") hide
      (effects (font (size 0.7 0.7) (thickness 0.15)) (justify left bottom))
    )
    (fp_text user "${REFERENCE}" (at -0.932 3.168 180) (layer "F.Fab") hide
      (effects (font (size 0.7 0.7) (thickness 0.15)) (justify left bottom))
    )
    (fp_text user "Author: Antmicro" (at -0.932 4.17 180) (layer "F.Fab") hide
      (effects (font (size 0.7 0.7) (thickness 0.15)) (justify left bottom))
    )
    (fp_rect (start -0.94 -0.47) (end 0.94 0.47) (layer "F.CrtYd") (width 0.05) (fill none))
    (fp_rect (start -0.499 -0.249) (end 0.499 0.249) (layer "F.Fab") (width 0.15) (fill none))
    (pad "1" smd roundrect (at -0.484 0 180) (size 0.59 0.64) (layers "F.Cu" "F.Paste" "F.Mask") (roundrect_rratio 0.25)
      (net 177 "/Ethernet Controller/ETH_3V3") (pintype "passive"))
    (pad "2" smd roundrect (at 0.484 0 180) (size 0.59 0.64) (layers "F.Cu" "F.Paste" "F.Mask") (roundrect_rratio 0.25)
      (net 1 "GND") (pintype "passive"))
  )
	(footprint "sa800u-baseboard-hw-footprints:FB_0603_1608Metric" (layer "F.Cu")
    (tedit 618B9E9E)
    (at 101.31 101.72 180)
    (property "Author" "Antmicro")
    (property "License" "Apache-2.0")
    (property "MPN" "BLM18SG121TN1D")
    (property "Manufacturer" "Murata")
    (property "Sheetfile" "ethernet-controller.kicad_sch")
    (property "Sheetname" "Ethernet Controller")
    (attr smd)
    (fp_text reference "FB1" (at -1.23 -0.36 180) (layer "F.SilkS")
      (effects (font (size 0.7 0.7) (thickness 0.15)) (justify left bottom))
    )
    (fp_text value "FB_120Z_3A_0603" (at 0 1.5 180) (layer "F.Fab")
      (effects (font (size 0.7 0.7) (thickness 0.15)) (justify left bottom))
    )
    (fp_text user "License: Apache-2.0" (at -1.653 5.9 180) (layer "F.Fab") hide
      (effects (font (size 0.7 0.7) (thickness 0.15)) (justify left bottom))
    )
    (fp_text user "${REFERENCE}" (at -1.653 4.6 180) (layer "F.Fab") hide
      (effects (font (size 0.7 0.7) (thickness 0.15)) (justify left bottom))
    )
    (fp_text user "Author: Antmicro" (at -1.653 3.162 180) (layer "F.Fab") hide
      (effects (font (size 0.7 0.7) (thickness 0.15)) (justify left bottom))
    )
    (fp_line (start -0.196 -0.408) (end 0.193 -0.408) (layer "F.SilkS") (width 0.15))
    (fp_line (start -0.196 0.406) (end 0.193 0.406) (layer "F.SilkS") (width 0.15))
    (fp_rect (start -1.3 -0.6) (end 1.3 0.6) (layer "F.CrtYd") (width 0.05) (fill none))
    (fp_line (start 0.8 0.406) (end -0.803 0.406) (layer "F.Fab") (width 0.15))
    (fp_line (start -0.803 0.406) (end -0.803 -0.408) (layer "F.Fab") (width 0.15))
    (fp_line (start 0.8 -0.408) (end -0.803 -0.408) (layer "F.Fab") (width 0.15))
    (fp_line (start 0.8 -0.408) (end 0.8 0.406) (layer "F.Fab") (width 0.15))
    (pad "1" smd roundrect (at -0.891 0 180) (size 0.762 1.09) (layers "F.Cu" "F.Paste" "F.Mask") (roundrect_rratio 0.15)
      (net 131 "3V3_SYS") (pintype "passive"))
    (pad "2" smd roundrect (at 0.888 0 180) (size 0.762 1.09) (layers "F.Cu" "F.Paste" "F.Mask") (roundrect_rratio 0.15)
      (net 177 "/Ethernet Controller/ETH_3V3") (pintype "passive"))
  )
	(footprint "sa800u-baseboard-hw-footprints:C_0402_1005Metric" (layer "F.Cu")
    (tedit 616D63CF)
    (at 96 101.35 -90)
    (descr "Capacitor SMD 0402")
    (tags "capacitor SMD 0402")
    (property "Author" "Antmicro")
    (property "Dielectric" "X5R")
    (property "License" "Apache-2.0")
    (property "MPN" "GRM155R61H104KE14D")
    (property "Manufacturer" "Murata")
    (property "Sheetfile" "ethernet-controller.kicad_sch")
    (property "Sheetname" "Ethernet Controller")
    (property "Val" "100n")
    (property "Voltage" "50V")
    (attr smd)
    (fp_text reference "C3" (at -0.87 -0.38 -90) (layer "F.SilkS")
      (effects (font (size 0.7 0.7) (thickness 0.15)) (justify left bottom))
    )
    (fp_text value "C_100n_0402" (at 0 1.4 -90) (layer "F.Fab")
      (effects (font (size 0.7 0.7) (thickness 0.15)) (justify left bottom))
    )
    (fp_text user "License: Apache-2.0" (at -0.932 5.17 -90) (layer "F.Fab") hide
      (effects (font (size 0.7 0.7) (thickness 0.15)) (justify left bottom))
    )
    (fp_text user "${REFERENCE}" (at -0.932 3.168 -90) (layer "F.Fab") hide
      (effects (font (size 0.7 0.7) (thickness 0.15)) (justify left bottom))
    )
    (fp_text user "Author: Antmicro" (at -0.932 4.17 -90) (layer "F.Fab") hide
      (effects (font (size 0.7 0.7) (thickness 0.15)) (justify left bottom))
    )
    (fp_rect (start -0.94 -0.47) (end 0.94 0.47) (layer "F.CrtYd") (width 0.05) (fill none))
    (fp_rect (start -0.499 -0.249) (end 0.499 0.249) (layer "F.Fab") (width 0.15) (fill none))
    (pad "1" smd roundrect (at -0.484 0 270) (size 0.59 0.64) (layers "F.Cu" "F.Paste" "F.Mask") (roundrect_rratio 0.25)
      (net 177 "/Ethernet Controller/ETH_3V3") (pintype "passive"))
    (pad "2" smd roundrect (at 0.484 0 270) (size 0.59 0.64) (layers "F.Cu" "F.Paste" "F.Mask") (roundrect_rratio 0.25)
      (net 1 "GND") (pintype "passive"))
  )
	(footprint "sa800u-baseboard-hw-footprints:Nexperia_DFN-10_2.5x1mm_P0.5mm" (layer "F.Cu")
    (tedit 6215DC23)
    (at 115.35 138.7 180)
    (property "Author" "Antmicro")
    (property "License" "Apache-2.0")
    (property "MPN" "PUSB3F96X")
    (property "Manufacturer" "Nexperia")
    (property "Sheetfile" "usb-c-interface.kicad_sch")
    (property "Sheetname" "USB-C Interface ")
    (attr smd)
    (fp_text reference "D12" (at -2.33 -0.98 270) (layer "F.SilkS")
      (effects (font (size 0.7 0.7) (thickness 0.15)) (justify left bottom))
    )
    (fp_text value "PUSB3F96X_PASS" (at -0.016 1.705 180) (layer "F.Fab")
      (effects (font (size 0.7 0.7) (thickness 0.15)) (justify left bottom))
    )
    (fp_text user "${REFERENCE}" (at -1.367 3.704 180) (layer "F.Fab") hide
      (effects (font (size 0.7 0.7) (thickness 0.15)) (justify left bottom))
    )
    (fp_text user "Author: Antmicro" (at -1.367 4.905 180) (layer "F.Fab") hide
      (effects (font (size 0.7 0.7) (thickness 0.15)) (justify left bottom))
    )
    (fp_text user "License: Apache-2.0" (at -1.367 6.105 180) (layer "F.Fab") hide
      (effects (font (size 0.7 0.7) (thickness 0.15)) (justify left bottom))
    )
    (fp_line (start 1.233 0.405) (end 1.233 -0.396) (layer "F.SilkS") (width 0.15))
    (fp_line (start -1.266 -0.396) (end -1.266 0.405) (layer "F.SilkS") (width 0.15))
    (fp_circle (center -1.317 0.704) (end -1.266 0.704) (layer "F.SilkS") (width 0.15) (fill solid))
    (fp_rect (start -1.4 -0.7) (end 1.4 0.7) (layer "F.CrtYd") (width 0.05) (fill none))
    (pad "1" smd rect (at -1.016 0.392 180) (size 0.2 0.475) (layers "F.Cu" "F.Paste" "F.Mask")
      (net 79 "USB2C_HS_D_N") (pinfunction "CH1") (pintype "passive"))
    (pad "2" smd rect (at -0.517 0.392 180) (size 0.2 0.475) (layers "F.Cu" "F.Paste" "F.Mask")
      (net 80 "USB2C_HS_D_P") (pinfunction "CH2") (pintype "passive"))
    (pad "3" smd rect (at -0.016 0.392 180) (size 0.2 0.475) (layers "F.Cu" "F.Paste" "F.Mask")
      (net 1 "GND") (pinfunction "GND") (pintype "passive"))
    (pad "4" smd rect (at 0.482 0.392 180) (size 0.2 0.475) (layers "F.Cu" "F.Paste" "F.Mask")
      (net 370 "unconnected-(D12-Pad4)") (pinfunction "CH3") (pintype "passive+no_connect"))
    (pad "5" smd rect (at 0.982 0.392 180) (size 0.2 0.475) (layers "F.Cu" "F.Paste" "F.Mask")
      (net 412 "unconnected-(D12-Pad5)") (pinfunction "CH4") (pintype "passive+no_connect"))
    (pad "6" smd rect (at 0.982 -0.383) (size 0.2 0.475) (layers "F.Cu" "F.Paste" "F.Mask")
      (net 412 "unconnected-(D12-Pad5)") (pinfunction "CH4") (pintype "passive+no_connect"))
    (pad "7" smd rect (at 0.482 -0.383) (size 0.2 0.475) (layers "F.Cu" "F.Paste" "F.Mask")
      (net 370 "unconnected-(D12-Pad4)") (pinfunction "CH3") (pintype "passive+no_connect"))
    (pad "8" smd rect (at -0.016 -0.383) (size 0.2 0.475) (layers "F.Cu" "F.Paste" "F.Mask")
      (net 1 "GND") (pinfunction "GND") (pintype "passive"))
    (pad "9" smd rect (at -0.517 -0.383) (size 0.2 0.475) (layers "F.Cu" "F.Paste" "F.Mask")
      (net 80 "USB2C_HS_D_P") (pinfunction "CH2") (pintype "passive"))
    (pad "10" smd rect (at -1.016 -0.383) (size 0.2 0.475) (layers "F.Cu" "F.Paste" "F.Mask")
      (net 79 "USB2C_HS_D_N") (pinfunction "CH1") (pintype "passive"))
  )
	(footprint "sa800u-baseboard-hw-footprints:C_0402_1005Metric" (layer "F.Cu")
    (tedit 616D63CF)
    (at 85.55 99.85 90)
    (descr "Capacitor SMD 0402")
    (tags "capacitor SMD 0402")
    (property "Author" "Antmicro")
    (property "Dielectric" "X5R")
    (property "License" "Apache-2.0")
    (property "MPN" "GRM155R61H104KE14D")
    (property "Manufacturer" "Murata")
    (property "Sheetfile" "psu.kicad_sch")
    (property "Sheetname" "PSU")
    (property "Val" "100n")
    (property "Voltage" "50V")
    (attr smd)
    (fp_text reference "C132" (at -0.44 1.36 90) (layer "F.SilkS")
      (effects (font (size 0.7 0.7) (thickness 0.15)) (justify left bottom))
    )
    (fp_text value "C_100n_0402" (at 0 1.4 90) (layer "F.Fab")
      (effects (font (size 0.7 0.7) (thickness 0.15)) (justify left bottom))
    )
    (fp_text user "${REFERENCE}" (at -0.932 3.168 90) (layer "F.Fab") hide
      (effects (font (size 0.7 0.7) (thickness 0.15)) (justify left bottom))
    )
    (fp_text user "Author: Antmicro" (at -0.932 4.17 90) (layer "F.Fab") hide
      (effects (font (size 0.7 0.7) (thickness 0.15)) (justify left bottom))
    )
    (fp_text user "License: Apache-2.0" (at -0.932 5.17 90) (layer "F.Fab") hide
      (effects (font (size 0.7 0.7) (thickness 0.15)) (justify left bottom))
    )
    (fp_rect (start -0.94 -0.47) (end 0.94 0.47) (layer "F.CrtYd") (width 0.05) (fill none))
    (fp_rect (start -0.499 -0.249) (end 0.499 0.249) (layer "F.Fab") (width 0.15) (fill none))
    (pad "1" smd roundrect (at -0.484 0 90) (size 0.59 0.64) (layers "F.Cu" "F.Paste" "F.Mask") (roundrect_rratio 0.25)
      (net 356 "Net-(C132-Pad1)") (pintype "passive"))
    (pad "2" smd roundrect (at 0.484 0 90) (size 0.59 0.64) (layers "F.Cu" "F.Paste" "F.Mask") (roundrect_rratio 0.25)
      (net 357 "Net-(C132-Pad2)") (pintype "passive"))
  )
	(footprint "sa800u-baseboard-hw-footprints:R_0402_1005Metric" (layer "F.Cu")
    (tedit 5FD9C158)
    (at 83.45 101.8 90)
    (descr "Resistor SMD 0402")
    (tags "resistor SMD 0402")
    (property "Author" "Antmicro")
    (property "DNP" "")
    (property "License" "Apache-2.0")
    (property "MPN" "CR0402-FX-1002GLF")
    (property "Manufacturer" "Bourns")
    (property "Sheetfile" "psu.kicad_sch")
    (property "Sheetname" "PSU")
    (property "Tolerance" "1%")
    (property "Val" "10k")
    (attr smd)
    (fp_text reference "R131" (at -1.07 4 90) (layer "F.SilkS")
      (effects (font (size 0.7 0.7) (thickness 0.15)) (justify left bottom))
    )
    (fp_text value "R_10k_0402" (at 0 1.4 90) (layer "F.Fab")
      (effects (font (size 0.7 0.7) (thickness 0.15)) (justify left bottom))
    )
    (fp_text user "License: Apache-2.0" (at -0.95 5.169 90) (layer "F.Fab") hide
      (effects (font (size 0.7 0.7) (thickness 0.15)) (justify left bottom))
    )
    (fp_text user "${REFERENCE}" (at -0.95 3.168 90) (layer "F.Fab") hide
      (effects (font (size 0.7 0.7) (thickness 0.15)) (justify left bottom))
    )
    (fp_text user "Author: Antmicro" (at -0.95 4.169 90) (layer "F.Fab") hide
      (effects (font (size 0.7 0.7) (thickness 0.15)) (justify left bottom))
    )
    (fp_rect (start -0.93 -0.47) (end 0.93 0.47) (layer "F.CrtYd") (width 0.05) (fill none))
    (fp_rect (start -0.5 -0.25) (end 0.5 0.25) (layer "F.Fab") (width 0.15) (fill none))
    (pad "1" smd roundrect (at -0.485 0 90) (size 0.59 0.64) (layers "F.Cu" "F.Paste" "F.Mask") (roundrect_rratio 0.25)
      (net 74 "VDD") (pintype "passive"))
    (pad "2" smd roundrect (at 0.485 0 90) (size 0.59 0.64) (layers "F.Cu" "F.Paste" "F.Mask") (roundrect_rratio 0.25)
      (net 409 "Net-(R131-Pad2)") (pintype "passive"))
  )
	(footprint "sa800u-baseboard-hw-footprints:R_0402_1005Metric" (layer "F.Cu")
    (tedit 5FD9C158)
    (at 81.95 101.3)
    (descr "Resistor SMD 0402")
    (tags "resistor SMD 0402")
    (property "Author" "Antmicro")
    (property "License" "Apache-2.0")
    (property "MPN" "CR0402-FX-7502GLF")
    (property "Manufacturer" "Bourns")
    (property "Sheetfile" "psu.kicad_sch")
    (property "Sheetname" "PSU")
    (property "Tolerance" "1%")
    (property "Val" "75k")
    (attr smd)
    (fp_text reference "R135" (at 1.92 0.4) (layer "F.SilkS")
      (effects (font (size 0.7 0.7) (thickness 0.15)) (justify left bottom))
    )
    (fp_text value "R_75k_0402" (at 0 1.4) (layer "F.Fab")
      (effects (font (size 0.7 0.7) (thickness 0.15)) (justify left bottom))
    )
    (fp_text user "Author: Antmicro" (at -0.95 4.169) (layer "F.Fab") hide
      (effects (font (size 0.7 0.7) (thickness 0.15)) (justify left bottom))
    )
    (fp_text user "License: Apache-2.0" (at -0.95 5.169) (layer "F.Fab") hide
      (effects (font (size 0.7 0.7) (thickness 0.15)) (justify left bottom))
    )
    (fp_text user "${REFERENCE}" (at -0.95 3.168) (layer "F.Fab") hide
      (effects (font (size 0.7 0.7) (thickness 0.15)) (justify left bottom))
    )
    (fp_rect (start -0.93 -0.47) (end 0.93 0.47) (layer "F.CrtYd") (width 0.05) (fill none))
    (fp_rect (start -0.5 -0.25) (end 0.5 0.25) (layer "F.Fab") (width 0.15) (fill none))
    (pad "1" smd roundrect (at -0.485 0) (size 0.59 0.64) (layers "F.Cu" "F.Paste" "F.Mask") (roundrect_rratio 0.25)
      (net 137 "3V8_SYS") (pintype "passive"))
    (pad "2" smd roundrect (at 0.485 0) (size 0.59 0.64) (layers "F.Cu" "F.Paste" "F.Mask") (roundrect_rratio 0.25)
      (net 171 "Net-(R135-Pad2)") (pintype "passive"))
  )
)
